(kicad_pcb
	(version 20260206)
	(generator "pcbnew")
	(generator_version "10.0")
	(general
		(thickness 1.21888)
		(legacy_teardrops no)
	)
	(paper "A4")
	(title_block
		(title "timecard-beta-v1 — TimeCard-DC-V1.PcbDoc")
		(comment 1 "Time Appliance Project (Time Card) / footprints 96-102 of 120")
	)
	(layers
		(0 "F.Cu" signal "TOP")
		(4 "In1.Cu" signal "SGND")
		(6 "In2.Cu" signal "IN1")
		(8 "In3.Cu" signal "IN2")
		(10 "In4.Cu" signal "SGND1")
		(2 "B.Cu" signal "BOTTOM")
		(9 "F.Adhes" user "F.Adhesive")
		(11 "B.Adhes" user "B.Adhesive")
		(13 "F.Paste" user "Top Paste")
		(15 "B.Paste" user "Bottom Paste")
		(5 "F.SilkS" user "Top Overlay")
		(7 "B.SilkS" user "Bottom Overlay")
		(1 "F.Mask" user "Top Solder")
		(3 "B.Mask" user "Bottom Solder")
		(17 "Dwgs.User" user "User.Drawings")
		(19 "Cmts.User" user "User.Comments")
		(21 "Eco1.User" user "User.Eco1")
		(23 "Eco2.User" user "User.Eco2")
		(25 "Edge.Cuts" user)
		(27 "Margin" user)
		(31 "F.CrtYd" user "Top Courtyard")
		(29 "B.CrtYd" user "Bottom Courtyard")
		(35 "F.Fab" user "Top Component Center")
		(33 "B.Fab" user "Bottom Component Center")
	)
	(footprint "Passives:DIOM1608X06N"
		(layer "F.Cu")
		(at 74.867595 53.2366 90)
		(property "Reference" "D11"
			(at -1.21245 -1.265735 90)
			(unlocked yes)
			(layer "F.SilkS")
			(effects
				(font
					(size 0.762 0.762)
					(thickness 0.2286)
				)
				(justify left bottom)
			)
		)
		(property "Value" "RED"
			(at -3.22199 -1.4097 0)
			(unlocked yes)
			(layer "F.SilkS")
			(hide yes)
			(effects
				(font
					(size 1.524 1.524)
					(thickness 0.254)
				)
				(justify left bottom)
			)
		)
		(sheetname "USER_IO")
		(sheetfile "USER_IO.kicad_sch")
		(duplicate_pad_numbers_are_jumpers no)
		(fp_circle
			(center -1.275 -0.725)
			(end -1.225 -0.725)
			(stroke
				(width 0.1)
				(type solid)
			)
			(fill no)
			(layer "F.SilkS")
		)
		(pad "1" smd rect
			(at -0.725 0 180)
			(size 0.85 1)
			(layers "F.Cu" "F.Mask" "F.Paste")
			(net "NetD11_1")
		)
		(pad "2" smd rect
			(at 0.725 0 180)
			(size 0.85 1)
			(layers "F.Cu" "F.Mask" "F.Paste")
			(net "+3.3V")
		)
	)
	(footprint "Vault:RESC1608X55X25NL10T15"
		(layer "F.Cu")
		(at 83.238595 136.8286 -90)
		(property "Reference" "R25"
			(at -2.9786 -0.026931 90)
			(unlocked yes)
			(layer "F.SilkS")
			(effects
				(font
					(size 0.762 0.762)
					(thickness 0.2286)
				)
			)
		)
		(property "Value" "49.9R"
			(at -2.911602 3.21199 180)
			(unlocked yes)
			(layer "F.SilkS")
			(hide yes)
			(effects
				(font
					(size 1.524 1.524)
					(thickness 0.254)
				)
			)
		)
		(sheetname "USER_IO")
		(sheetfile "USER_IO.kicad_sch")
		(duplicate_pad_numbers_are_jumpers no)
		(pad "1" smd rect
			(at -0.7 0)
			(size 0.9 0.7)
			(layers "F.Cu" "F.Mask" "F.Paste")
			(net "NetR25_1")
		)
		(pad "2" smd rect
			(at 0.7 0)
			(size 0.9 0.7)
			(layers "F.Cu" "F.Mask" "F.Paste")
			(net "NetAN4_1")
		)
	)
	(footprint "Vault:CAPC1608X87X45ML20T05"
		(layer "F.Cu")
		(at 148.288595 85.5786 180)
		(property "Reference" "C30"
			(at 2.8214 -0.026931 0)
			(unlocked yes)
			(layer "F.SilkS")
			(effects
				(font
					(size 0.762 0.762)
					(thickness 0.2286)
				)
			)
		)
		(property "Value" "0.1uF"
			(at 2.09443 2.657602 180)
			(unlocked yes)
			(layer "F.SilkS")
			(hide yes)
			(effects
				(font
					(size 1.524 1.524)
					(thickness 0.254)
				)
			)
		)
		(sheetname "GPS_IMU_SENSORS")
		(sheetfile "GPS_IMU_SENSORS.kicad_sch")
		(duplicate_pad_numbers_are_jumpers no)
		(pad "1" smd rect
			(at -0.7 0 270)
			(size 1.1 1.05)
			(layers "F.Cu" "F.Mask" "F.Paste")
			(net "GND")
		)
		(pad "2" smd rect
			(at 0.7 0 270)
			(size 1.1 1.05)
			(layers "F.Cu" "F.Mask" "F.Paste")
			(net "+3.3V")
		)
	)
	(footprint "Vault:CAPC1608X90X35NL10T15"
		(layer "F.Cu")
		(at 234.760595 112.1646 -90)
		(property "Reference" "C20"
			(at -1.336 -0.346345 90)
			(unlocked yes)
			(layer "F.SilkS")
			(effects
				(font
					(size 0.762 0.762)
					(thickness 0.2286)
				)
				(justify left bottom)
			)
		)
		(property "Value" "0.033uF"
			(at 3.34899 3.7211 0)
			(unlocked yes)
			(layer "F.SilkS")
			(hide yes)
			(effects
				(font
					(size 1.524 1.524)
					(thickness 0.254)
				)
				(justify left bottom)
			)
		)
		(sheetname "POWER")
		(sheetfile "POWER.kicad_sch")
		(duplicate_pad_numbers_are_jumpers no)
		(pad "1" smd rect
			(at -0.675 0)
			(size 0.95 0.85)
			(layers "F.Cu" "F.Mask" "F.Paste")
			(net "NetC20_1")
		)
		(pad "2" smd rect
			(at 0.675 0)
			(size 0.95 0.85)
			(layers "F.Cu" "F.Mask" "F.Paste")
			(net "NetC20_2")
		)
	)
	(footprint "Connectors:AMPHENOL-901-143-6RFX"
		(layer "F.Cu")
		(at 63.564595 124.2296 180)
		(property "Reference" "AN3"
			(at 4.076 -6.192345 0)
			(unlocked yes)
			(layer "F.SilkS")
			(effects
				(font
					(size 0.762 0.762)
					(thickness 0.2286)
				)
				(justify left bottom)
			)
		)
		(property "Value" "901-143-6RFX"
			(at 4.6101 -2.05359 0)
			(unlocked yes)
			(layer "F.SilkS")
			(hide yes)
			(effects
				(font
					(size 1.524 1.524)
					(thickness 0.254)
				)
				(justify left bottom)
			)
		)
		(sheetname "USER_IO")
		(sheetfile "USER_IO.kicad_sch")
		(duplicate_pad_numbers_are_jumpers no)
		(fp_line
			(start 4.318 3.556)
			(end 3.302 4.572)
			(stroke
				(width 0.1778)
				(type solid)
			)
			(layer "F.SilkS")
		)
		(fp_line
			(start 4.318 -3.556)
			(end 3.302 -4.572)
			(stroke
				(width 0.1778)
				(type solid)
			)
			(layer "F.SilkS")
		)
		(fp_line
			(start 3.302 4.572)
			(end 2.54 4.572)
			(stroke
				(width 0.1778)
				(type solid)
			)
			(layer "F.SilkS")
		)
		(fp_line
			(start 3.302 -4.572)
			(end 2.54 -4.572)
			(stroke
				(width 0.1778)
				(type solid)
			)
			(layer "F.SilkS")
		)
		(fp_line
			(start 2.54 4.572)
			(end -4.572 4.572)
			(stroke
				(width 0.1778)
				(type solid)
			)
			(layer "F.SilkS")
		)
		(fp_line
			(start 2.54 -4.572)
			(end -4.572 -4.572)
			(stroke
				(width 0.1778)
				(type solid)
			)
			(layer "F.SilkS")
		)
		(fp_line
			(start -4.572 2.54)
			(end -4.572 4.572)
			(stroke
				(width 0.1778)
				(type solid)
			)
			(layer "F.SilkS")
		)
		(fp_line
			(start -4.572 -4.572)
			(end -4.572 -2.54)
			(stroke
				(width 0.1778)
				(type solid)
			)
			(layer "F.SilkS")
		)
		(pad "1" thru_hole circle
			(at 0 0 180)
			(size 2.8448 2.8448)
			(drill 1.524)
			(layers "*.Cu" "*.Mask")
			(remove_unused_layers no)
			(net "NetAN3_1")
			(thermal_bridge_angle 90)
		)
		(pad "2" thru_hole circle
			(at -2.54 2.54 180)
			(size 3.048 3.048)
			(drill 1.7272)
			(layers "*.Cu" "*.Mask")
			(remove_unused_layers no)
			(net "GND")
			(thermal_bridge_angle 90)
		)
		(pad "3" thru_hole circle
			(at -2.54 -2.54 180)
			(size 3.048 3.048)
			(drill 1.7272)
			(layers "*.Cu" "*.Mask")
			(remove_unused_layers no)
			(net "GND")
			(thermal_bridge_angle 90)
		)
		(pad "4" thru_hole circle
			(at 2.54 -2.54 180)
			(size 3.048 3.048)
			(drill 1.7272)
			(layers "*.Cu" "*.Mask")
			(remove_unused_layers no)
			(net "GND")
			(thermal_bridge_angle 90)
		)
		(pad "5" thru_hole circle
			(at 2.54 2.54 180)
			(size 3.048 3.048)
			(drill 1.7272)
			(layers "*.Cu" "*.Mask")
			(remove_unused_layers no)
			(net "GND")
			(thermal_bridge_angle 90)
		)
	)
	(footprint "Vault:RESC1608X55X30NL15T15"
		(layer "F.Cu")
		(at 90.188595 56.9786 90)
		(property "Reference" "R30"
			(at -1.3 -1.206655 90)
			(unlocked yes)
			(layer "F.SilkS")
			(effects
				(font
					(size 0.762 0.762)
					(thickness 0.2286)
				)
				(justify left bottom)
			)
		)
		(property "Value" "200 OHM"
			(at -3.72999 -0.4445 0)
			(unlocked yes)
			(layer "F.SilkS")
			(hide yes)
			(effects
				(font
					(size 1.524 1.524)
					(thickness 0.254)
				)
				(justify left bottom)
			)
		)
		(sheetname "USER_IO")
		(sheetfile "USER_IO.kicad_sch")
		(duplicate_pad_numbers_are_jumpers no)
		(pad "1" smd rect
			(at -0.675 0 180)
			(size 0.95 0.8)
			(layers "F.Cu" "F.Mask" "F.Paste")
			(net "LED4")
		)
		(pad "2" smd rect
			(at 0.675 0 180)
			(size 0.95 0.8)
			(layers "F.Cu" "F.Mask" "F.Paste")
			(net "NetD14_1")
		)
	)
	(footprint "Vault:M08A_N"
		(layer "F.Cu")
		(at 196.888595 88.7136)
		(property "Reference" "U3"
			(at 1.578605 -3.608069 0)
			(unlocked yes)
			(layer "F.SilkS")
			(effects
				(font
					(size 0.762 0.762)
					(thickness 0.2286)
				)
			)
		)
		(property "Value" "DS90LV027AQMA"
			(at 6.38498 4.359402 0)
			(unlocked yes)
			(layer "F.SilkS")
			(hide yes)
			(effects
				(font
					(size 1.524 1.524)
					(thickness 0.254)
				)
			)
		)
		(sheetname "MAC")
		(sheetfile "MAC.kicad_sch")
		(duplicate_pad_numbers_are_jumpers no)
		(fp_line
			(start -0.9 -2.5)
			(end 0.9 -2.5)
			(stroke
				(width 0.2)
				(type solid)
			)
			(layer "F.SilkS")
		)
		(fp_line
			(start -0.9 2.5)
			(end -0.9 -2.5)
			(stroke
				(width 0.2)
				(type solid)
			)
			(layer "F.SilkS")
		)
		(fp_line
			(start -0.9 2.5)
			(end 0.9 2.5)
			(stroke
				(width 0.2)
				(type solid)
			)
			(layer "F.SilkS")
		)
		(fp_line
			(start 0.9 2.5)
			(end 0.9 -2.5)
			(stroke
				(width 0.2)
				(type solid)
			)
			(layer "F.SilkS")
		)
		(fp_circle
			(center -2.4 -2.755)
			(end -2.4 -2.88)
			(stroke
				(width 0.25)
				(type solid)
			)
			(fill no)
			(layer "F.SilkS")
		)
		(fp_circle
			(center -0.1 -1.7)
			(end -0.1 -1.9)
			(stroke
				(width 0.4)
				(type solid)
			)
			(fill no)
			(layer "F.SilkS")
		)
		(pad "1" smd oval
			(at -2.4 -1.905 90)
			(size 0.6 2.2)
			(layers "F.Cu" "F.Mask" "F.Paste")
			(net "+3.3V")
		)
		(pad "2" smd oval
			(at -2.4 -0.635 90)
			(size 0.6 2.2)
			(layers "F.Cu" "F.Mask" "F.Paste")
			(net "FPGA_MAC_PPS_IN1-")
		)
		(pad "3" smd oval
			(at -2.4 0.635 90)
			(size 0.6 2.2)
			(layers "F.Cu" "F.Mask" "F.Paste")
			(net "FPGA_MAC_PPS_IN0-")
		)
		(pad "4" smd oval
			(at -2.4 1.905 90)
			(size 0.6 2.2)
			(layers "F.Cu" "F.Mask" "F.Paste")
			(net "GND")
		)
		(pad "5" smd oval
			(at 2.4 1.905 90)
			(size 0.6 2.2)
			(layers "F.Cu" "F.Mask" "F.Paste")
			(net "MAC_PPS_IN0-")
		)
		(pad "6" smd oval
			(at 2.4 0.635 90)
			(size 0.6 2.2)
			(layers "F.Cu" "F.Mask" "F.Paste")
			(net "MAC_PPS_IN0+")
		)
		(pad "7" smd oval
			(at 2.4 -0.635 90)
			(size 0.6 2.2)
			(layers "F.Cu" "F.Mask" "F.Paste")
			(net "MAC_PPS_IN1+")
		)
		(pad "8" smd oval
			(at 2.4 -1.905 90)
			(size 0.6 2.2)
			(layers "F.Cu" "F.Mask" "F.Paste")
			(net "MAC_PPS_IN1-")
		)
	)
)
